(kicad_pcb
	(version 20241229)
	(generator "pcbnew")
	(generator_version "9.0")
	(general
		(thickness 1.552)
		(legacy_teardrops no)
	)
	(paper "A4")
	(title_block
		(date "2023-07-25")
		(rev "1.1.4")
		(comment 9 "footprints 219-223 of 379")
	)
	(layers
		(0 "F.Cu" signal)
		(4 "In1.Cu" signal)
		(6 "In2.Cu" signal)
		(8 "In3.Cu" signal)
		(10 "In4.Cu" signal)
		(12 "In5.Cu" signal)
		(14 "In6.Cu" signal)
		(2 "B.Cu" signal)
		(9 "F.Adhes" user "F.Adhesive")
		(11 "B.Adhes" user "B.Adhesive")
		(13 "F.Paste" user)
		(15 "B.Paste" user)
		(5 "F.SilkS" user "F.Silkscreen")
		(7 "B.SilkS" user "B.Silkscreen")
		(1 "F.Mask" user)
		(3 "B.Mask" user)
		(17 "Dwgs.User" user "User.Drawings")
		(19 "Cmts.User" user "User.Comments")
		(21 "Eco1.User" user "User.Eco1")
		(23 "Eco2.User" user "User.Eco2")
		(25 "Edge.Cuts" user)
		(27 "Margin" user)
		(31 "F.CrtYd" user "F.Courtyard")
		(29 "B.CrtYd" user "B.Courtyard")
		(35 "F.Fab" user)
		(33 "B.Fab" user)
	)
	(footprint "antmicro-footprints:C_0603_1608Metric"
		(layer "F.Cu")
		(at 153.59 74.54)
		(descr "Capacitor SMD 0603")
		(tags "capacitor 0603")
		(property "Reference" "C10"
			(at -1.16 1.6 0)
			(layer "F.SilkS")
			(effects
				(font
					(size 0.65 0.65)
					(thickness 0.15)
				)
				(justify left bottom)
			)
		)
		(property "Value" "C_10u_0603"
			(at 0 1.6 0)
			(layer "F.Fab")
			(hide yes)
			(effects
				(font
					(size 0.7 0.7)
					(thickness 0.15)
				)
				(justify left bottom)
			)
		)
		(property "Datasheet" "https://www.murata.com/products/productdetail?partno=GRM188R61A106KE69%23"
			(at 0 0 0)
			(layer "F.Fab")
			(hide yes)
			(effects
				(font
					(size 1.27 1.27)
					(thickness 0.15)
				)
			)
		)
		(property "Description" "SMD Multilayer Ceramic Capacitor, 10 µF, 10 V, 0603 [1608 Metric], ± 10%, X5R, GRM Series"
			(at 0 0 0)
			(layer "F.Fab")
			(hide yes)
			(effects
				(font
					(size 1.27 1.27)
					(thickness 0.15)
				)
			)
		)
		(property "Author" "Antmicro"
			(at 0 0 0)
			(layer "F.Fab")
			(hide yes)
			(effects
				(font
					(size 1 1)
					(thickness 0.15)
				)
			)
		)
		(property "License" "Apache-2.0"
			(at 0 0 0)
			(layer "F.Fab")
			(hide yes)
			(effects
				(font
					(size 1 1)
					(thickness 0.15)
				)
			)
		)
		(property "MPN" "GRM188R61A106KE69D"
			(at 0 0 0)
			(layer "F.Fab")
			(hide yes)
			(effects
				(font
					(size 1 1)
					(thickness 0.15)
				)
			)
		)
		(property "Manufacturer" "Murata"
			(at 0 0 0)
			(layer "F.Fab")
			(hide yes)
			(effects
				(font
					(size 1 1)
					(thickness 0.15)
				)
			)
		)
		(property "Val" "10u"
			(at 0 0 0)
			(layer "F.Fab")
			(hide yes)
			(effects
				(font
					(size 1 1)
					(thickness 0.15)
				)
			)
		)
		(property "Voltage" ""
			(at 0 0 0)
			(layer "F.Fab")
			(hide yes)
			(effects
				(font
					(size 1 1)
					(thickness 0.15)
				)
			)
		)
		(property "Dielectric" "template_dielectric"
			(at 0 0 0)
			(unlocked yes)
			(layer "F.Fab")
			(hide yes)
			(effects
				(font
					(size 1 1)
					(thickness 0.15)
				)
			)
		)
		(sheetname "/Power Supply/")
		(sheetfile "supply.kicad_sch")
		(attr smd)
		(fp_line
			(start -0.15 -0.4)
			(end 0.15 -0.4)
			(stroke
				(width 0.15)
				(type solid)
			)
			(layer "F.SilkS")
		)
		(fp_line
			(start -0.15 0.4)
			(end 0.15 0.4)
			(stroke
				(width 0.15)
				(type solid)
			)
			(layer "F.SilkS")
		)
		(fp_rect
			(start -1.25 -0.65)
			(end 1.25 0.65)
			(stroke
				(width 0.05)
				(type solid)
			)
			(fill no)
			(layer "F.CrtYd")
		)
		(fp_rect
			(start -0.8 -0.4)
			(end 0.8 0.4)
			(stroke
				(width 0.15)
				(type solid)
			)
			(fill no)
			(layer "F.Fab")
		)
		(fp_text user "License: Apache-2.0"
			(at -1.682 5.895 0)
			(layer "F.Fab")
			(effects
				(font
					(size 0.7 0.7)
					(thickness 0.15)
				)
				(justify left bottom)
			)
		)
		(fp_text user "${REFERENCE}"
			(at -1.682 3.895 0)
			(layer "F.Fab")
			(effects
				(font
					(size 0.7 0.7)
					(thickness 0.15)
				)
				(justify left bottom)
			)
		)
		(fp_text user "Author: Antmicro"
			(at -1.682 4.894 0)
			(layer "F.Fab")
			(effects
				(font
					(size 0.7 0.7)
					(thickness 0.15)
				)
				(justify left bottom)
			)
		)
		(pad "1" smd roundrect
			(at -0.7 0)
			(size 0.8 1)
			(layers "F.Cu" "F.Mask" "F.Paste")
			(roundrect_rratio 0.2)
			(net 14 "+5V")
			(pintype "passive")
		)
		(pad "2" smd roundrect
			(at 0.7 0)
			(size 0.8 1)
			(layers "F.Cu" "F.Mask" "F.Paste")
			(roundrect_rratio 0.2)
			(net 1 "GND")
			(pintype "passive")
		)
	)
	(footprint "antmicro-footprints:C_0402_1005Metric"
		(layer "F.Cu")
		(at 106.49 98.7)
		(descr "Capacitor SMD 0402")
		(tags "capacitor SMD 0402")
		(property "Reference" "C82"
			(at 0.24 1.34 0)
			(layer "F.SilkS")
			(effects
				(font
					(size 0.65 0.65)
					(thickness 0.15)
				)
				(justify left bottom)
			)
		)
		(property "Value" "C_100n_0402"
			(at 0 1.4 0)
			(layer "F.Fab")
			(hide yes)
			(effects
				(font
					(size 0.7 0.7)
					(thickness 0.15)
				)
				(justify left bottom)
			)
		)
		(property "Datasheet" "https://www.murata.com/products/productdetail?partno=GRM155R61H104KE14%23"
			(at 0 0 0)
			(layer "F.Fab")
			(hide yes)
			(effects
				(font
					(size 1.27 1.27)
					(thickness 0.15)
				)
			)
		)
		(property "Description" "SMD Multilayer Ceramic Capacitor, 0.1 µF, 50 V, 0402 [1005 Metric], ± 10%, X5R, GRM Series"
			(at 0 0 0)
			(layer "F.Fab")
			(hide yes)
			(effects
				(font
					(size 1.27 1.27)
					(thickness 0.15)
				)
			)
		)
		(property "Author" "Antmicro"
			(at 0 0 0)
			(layer "F.Fab")
			(hide yes)
			(effects
				(font
					(size 1 1)
					(thickness 0.15)
				)
			)
		)
		(property "Dielectric" "X5R"
			(at 0 0 0)
			(layer "F.Fab")
			(hide yes)
			(effects
				(font
					(size 1 1)
					(thickness 0.15)
				)
			)
		)
		(property "License" "Apache-2.0"
			(at 0 0 0)
			(layer "F.Fab")
			(hide yes)
			(effects
				(font
					(size 1 1)
					(thickness 0.15)
				)
			)
		)
		(property "MPN" "GRM155R61H104KE14D"
			(at 0 0 0)
			(layer "F.Fab")
			(hide yes)
			(effects
				(font
					(size 1 1)
					(thickness 0.15)
				)
			)
		)
		(property "Manufacturer" "Murata"
			(at 0 0 0)
			(layer "F.Fab")
			(hide yes)
			(effects
				(font
					(size 1 1)
					(thickness 0.15)
				)
			)
		)
		(property "Val" "100n"
			(at 0 0 0)
			(layer "F.Fab")
			(hide yes)
			(effects
				(font
					(size 1 1)
					(thickness 0.15)
				)
			)
		)
		(property "Voltage" "50V"
			(at 0 0 0)
			(layer "F.Fab")
			(hide yes)
			(effects
				(font
					(size 1 1)
					(thickness 0.15)
				)
			)
		)
		(sheetname "/FPGA/")
		(sheetfile "fpga.kicad_sch")
		(attr smd)
		(fp_rect
			(start -0.925 -0.47)
			(end 0.925 0.47)
			(stroke
				(width 0.05)
				(type default)
			)
			(fill no)
			(layer "F.CrtYd")
		)
		(fp_line
			(start -0.494 -0.25)
			(end 0.504 -0.25)
			(stroke
				(width 0.15)
				(type solid)
			)
			(layer "F.Fab")
		)
		(fp_line
			(start -0.494 0.248)
			(end -0.494 -0.25)
			(stroke
				(width 0.15)
				(type solid)
			)
			(layer "F.Fab")
		)
		(fp_line
			(start 0.504 -0.25)
			(end 0.504 0.248)
			(stroke
				(width 0.15)
				(type solid)
			)
			(layer "F.Fab")
		)
		(fp_line
			(start 0.504 0.248)
			(end -0.494 0.248)
			(stroke
				(width 0.15)
				(type solid)
			)
			(layer "F.Fab")
		)
		(fp_text user "${REFERENCE}"
			(at -0.939 4.599 0)
			(layer "F.Fab")
			(effects
				(font
					(size 0.7 0.7)
					(thickness 0.15)
				)
				(justify left bottom)
			)
		)
		(fp_text user "License: Apache-2.0"
			(at -0.939 5.799 0)
			(layer "F.Fab")
			(effects
				(font
					(size 0.7 0.7)
					(thickness 0.15)
				)
				(justify left bottom)
			)
		)
		(fp_text user "Author: Antmicro"
			(at -0.939 3.399 0)
			(layer "F.Fab")
			(effects
				(font
					(size 0.7 0.7)
					(thickness 0.15)
				)
				(justify left bottom)
			)
		)
		(pad "1" smd roundrect
			(at -0.48 0)
			(size 0.59 0.64)
			(layers "F.Cu" "F.Mask" "F.Paste")
			(roundrect_rratio 0.25)
			(net 1 "GND")
			(pintype "passive")
		)
		(pad "2" smd roundrect
			(at 0.48 0)
			(size 0.59 0.64)
			(layers "F.Cu" "F.Mask" "F.Paste")
			(roundrect_rratio 0.25)
			(net 2 "+3V3")
			(pintype "passive")
		)
	)
	(footprint "antmicro-footprints:R_0603_1608Metric"
		(layer "F.Cu")
		(at 141.46 81)
		(descr "Resistor SMD 0603")
		(tags "resistor SMD 0603")
		(property "Reference" "R135"
			(at 1.27 0.44 0)
			(layer "F.SilkS")
			(effects
				(font
					(size 0.65 0.65)
					(thickness 0.15)
				)
				(justify left bottom)
			)
		)
		(property "Value" "R_200R_0603"
			(at 0 1.6 0)
			(layer "F.Fab")
			(hide yes)
			(effects
				(font
					(size 0.7 0.7)
					(thickness 0.15)
				)
				(justify left bottom)
			)
		)
		(property "Datasheet" "https://www.bourns.com/docs/product-datasheets/cr.pdf"
			(at 0 0 0)
			(layer "F.Fab")
			(hide yes)
			(effects
				(font
					(size 1.27 1.27)
					(thickness 0.15)
				)
			)
		)
		(property "Description" "SMD Chip Resistor, 200 ohm, ± 1%, 100 mW, 0603 [1608 Metric], Thick Film, General Purpose"
			(at 0 0 0)
			(layer "F.Fab")
			(hide yes)
			(effects
				(font
					(size 1.27 1.27)
					(thickness 0.15)
				)
			)
		)
		(property "Author" "Antmicro"
			(at 0 0 0)
			(layer "F.Fab")
			(hide yes)
			(effects
				(font
					(size 1 1)
					(thickness 0.15)
				)
			)
		)
		(property "License" "Apache-2.0"
			(at 0 0 0)
			(layer "F.Fab")
			(hide yes)
			(effects
				(font
					(size 1 1)
					(thickness 0.15)
				)
			)
		)
		(property "MPN" "CR0603-FX-2000ELF"
			(at 0 0 0)
			(layer "F.Fab")
			(hide yes)
			(effects
				(font
					(size 1 1)
					(thickness 0.15)
				)
			)
		)
		(property "Manufacturer" "Bourns"
			(at 0 0 0)
			(layer "F.Fab")
			(hide yes)
			(effects
				(font
					(size 1 1)
					(thickness 0.15)
				)
			)
		)
		(property "Tolerance" "1%"
			(at 0 0 0)
			(layer "F.Fab")
			(hide yes)
			(effects
				(font
					(size 1 1)
					(thickness 0.15)
				)
			)
		)
		(property "Val" "200R"
			(at 0 0 0)
			(layer "F.Fab")
			(hide yes)
			(effects
				(font
					(size 1 1)
					(thickness 0.15)
				)
			)
		)
		(sheetname "/Peripherals/")
		(sheetfile "peripherals.kicad_sch")
		(attr smd)
		(fp_line
			(start -0.15 -0.4)
			(end 0.15 -0.4)
			(stroke
				(width 0.15)
				(type solid)
			)
			(layer "F.SilkS")
		)
		(fp_line
			(start -0.15 0.4)
			(end 0.15 0.4)
			(stroke
				(width 0.15)
				(type solid)
			)
			(layer "F.SilkS")
		)
		(fp_rect
			(start -1.25 -0.65)
			(end 1.25 0.65)
			(stroke
				(width 0.05)
				(type solid)
			)
			(fill no)
			(layer "F.CrtYd")
		)
		(fp_rect
			(start -0.8 -0.4)
			(end 0.8 0.4)
			(stroke
				(width 0.15)
				(type solid)
			)
			(fill no)
			(layer "F.Fab")
		)
		(fp_text user "License: Apache-2.0"
			(at -1.25 5.9 0)
			(layer "F.Fab")
			(effects
				(font
					(size 0.7 0.7)
					(thickness 0.15)
				)
				(justify left bottom)
			)
		)
		(fp_text user "Author: Antmicro"
			(at -1.25 4.9 0)
			(layer "F.Fab")
			(effects
				(font
					(size 0.7 0.7)
					(thickness 0.15)
				)
				(justify left bottom)
			)
		)
		(fp_text user "${REFERENCE}"
			(at -1.25 3.898 0)
			(layer "F.Fab")
			(effects
				(font
					(size 0.7 0.7)
					(thickness 0.15)
				)
				(justify left bottom)
			)
		)
		(pad "1" smd roundrect
			(at -0.7 0)
			(size 0.8 1)
			(layers "F.Cu" "F.Mask" "F.Paste")
			(roundrect_rratio 0.2)
			(net 294 "Net-(D12-A)")
			(pintype "passive")
		)
		(pad "2" smd roundrect
			(at 0.7 0)
			(size 0.8 1)
			(layers "F.Cu" "F.Mask" "F.Paste")
			(roundrect_rratio 0.2)
			(net 348 "/Peripherals/FTDI_VCCIO")
			(pintype "passive")
		)
	)
	(footprint "antmicro-footprints:SOT-23-5"
		(layer "F.Cu")
		(at 141.69 110.7 180)
		(property "Reference" "U10"
			(at -2.14 -2.64 0)
			(layer "F.SilkS")
			(effects
				(font
					(size 0.65 0.65)
					(thickness 0.15)
				)
				(justify right bottom)
			)
		)
		(property "Value" "AP7330-W5-7"
			(at 0.002 2.799 0)
			(layer "F.Fab")
			(hide yes)
			(effects
				(font
					(size 0.7 0.7)
					(thickness 0.15)
				)
				(justify right bottom)
			)
		)
		(property "Datasheet" "https://www.diodes.com/assets/Datasheets/AP7330.pdf"
			(at 0 0 180)
			(layer "F.Fab")
			(hide yes)
			(effects
				(font
					(size 1.27 1.27)
					(thickness 0.15)
				)
			)
		)
		(property "Description" "Voltage regulator"
			(at 0 0 180)
			(layer "F.Fab")
			(hide yes)
			(effects
				(font
					(size 1.27 1.27)
					(thickness 0.15)
				)
			)
		)
		(property "Author" "Antmicro"
			(at 283.38 221.4 0)
			(layer "F.Fab")
			(hide yes)
			(effects
				(font
					(size 1 1)
					(thickness 0.15)
				)
			)
		)
		(property "License" "Apache-2.0"
			(at 283.38 221.4 0)
			(layer "F.Fab")
			(hide yes)
			(effects
				(font
					(size 1 1)
					(thickness 0.15)
				)
			)
		)
		(property "MPN" "AP7330-W5-7"
			(at 283.38 221.4 0)
			(layer "F.Fab")
			(hide yes)
			(effects
				(font
					(size 1 1)
					(thickness 0.15)
				)
			)
		)
		(property "Manufacturer" "Diodes Incorporated"
			(at 283.38 221.4 0)
			(layer "F.Fab")
			(hide yes)
			(effects
				(font
					(size 1 1)
					(thickness 0.15)
				)
			)
		)
		(sheetname "/Power Supply/")
		(sheetfile "supply.kicad_sch")
		(attr smd)
		(fp_line
			(start 0.8 1.599)
			(end 0.549 1.599)
			(stroke
				(width 0.15)
				(type solid)
			)
			(layer "F.SilkS")
		)
		(fp_line
			(start 0.8 1.3)
			(end 0.8 1.599)
			(stroke
				(width 0.15)
				(type solid)
			)
			(layer "F.SilkS")
		)
		(fp_line
			(start 0.8 0.55)
			(end 0.8 -0.55)
			(stroke
				(width 0.15)
				(type solid)
			)
			(layer "F.SilkS")
		)
		(fp_line
			(start 0.8 -1.3)
			(end 0.8 -1.6)
			(stroke
				(width 0.15)
				(type solid)
			)
			(layer "F.SilkS")
		)
		(fp_line
			(start 0.8 -1.6)
			(end 0.5 -1.6)
			(stroke
				(width 0.15)
				(type solid)
			)
			(layer "F.SilkS")
		)
		(fp_line
			(start -0.55 1.6)
			(end -0.85 1.6)
			(stroke
				(width 0.15)
				(type solid)
			)
			(layer "F.SilkS")
		)
		(fp_line
			(start -0.8 -1.6)
			(end -0.5 -1.6)
			(stroke
				(width 0.15)
				(type solid)
			)
			(layer "F.SilkS")
		)
		(fp_line
			(start -0.8 -1.6)
			(end -0.8 -1.3)
			(stroke
				(width 0.15)
				(type solid)
			)
			(layer "F.SilkS")
		)
		(fp_line
			(start -0.85 1.6)
			(end -0.85 1.301)
			(stroke
				(width 0.15)
				(type solid)
			)
			(layer "F.SilkS")
		)
		(fp_circle
			(center -1.25 -1.5)
			(end -1.2 -1.5)
			(stroke
				(width 0.15)
				(type solid)
			)
			(fill yes)
			(layer "F.SilkS")
		)
		(fp_rect
			(start 1.9 -1.76)
			(end -1.9 1.75)
			(stroke
				(width 0.05)
				(type solid)
			)
			(fill no)
			(layer "F.CrtYd")
		)
		(fp_line
			(start -0.398 -1.526)
			(end -0.874 -1.05)
			(stroke
				(width 0.15)
				(type solid)
			)
			(layer "F.Fab")
		)
		(fp_rect
			(start 0.874 1.523)
			(end -0.873 -1.525)
			(stroke
				(width 0.15)
				(type solid)
			)
			(fill no)
			(layer "F.Fab")
		)
		(pad "1" smd rect
			(at -1.351 -0.951 90)
			(size 0.55 1)
			(layers "F.Cu" "F.Mask" "F.Paste")
			(net 266 "Net-(U10-V_{IN})")
			(pinfunction "V_{IN}")
			(pintype "power_in")
		)
		(pad "2" smd rect
			(at -1.351 0 90)
			(size 0.55 1)
			(layers "F.Cu" "F.Mask" "F.Paste")
			(net 1 "GND")
			(pinfunction "GND")
			(pintype "power_in")
		)
		(pad "3" smd rect
			(at -1.351 0.949 90)
			(size 0.55 1)
			(layers "F.Cu" "F.Mask" "F.Paste")
			(net 271 "Net-(U10-EN)")
			(pinfunction "EN")
			(pintype "input")
		)
		(pad "4" smd rect
			(at 1.35 0.949 90)
			(size 0.55 1)
			(layers "F.Cu" "F.Mask" "F.Paste")
			(net 283 "Net-(U10-ADJ)")
			(pinfunction "ADJ")
			(pintype "passive")
		)
		(pad "5" smd rect
			(at 1.35 -0.951 90)
			(size 0.55 1)
			(layers "F.Cu" "F.Mask" "F.Paste")
			(net 284 "Net-(U10-V_{OUT})")
			(pinfunction "V_{OUT}")
			(pintype "power_out")
		)
	)
	(footprint "antmicro-footprints:R_0402_1005Metric"
		(layer "F.Cu")
		(at 167.2 92.6 180)
		(descr "Resistor SMD 0402")
		(tags "resistor SMD 0402")
		(property "Reference" "R123"
			(at 3.67 -0.34 180)
			(layer "F.SilkS")
			(effects
				(font
					(size 0.65 0.65)
					(thickness 0.15)
				)
				(justify left bottom)
			)
		)
		(property "Value" "R_0R_0402"
			(at 0 1.4 180)
			(layer "F.Fab")
			(hide yes)
			(effects
				(font
					(size 0.7 0.7)
					(thickness 0.15)
				)
				(justify left bottom)
			)
		)
		(property "Datasheet" "https://industrial.panasonic.com/cdbs/www-data/pdf/RDA0000/AOA0000C301.pdf"
			(at 0 0 180)
			(layer "F.Fab")
			(hide yes)
			(effects
				(font
					(size 1.27 1.27)
					(thickness 0.15)
				)
			)
		)
		(property "Description" "SMD Chip Resistor, Jumper, 0 ohm, 100 mW, 0402 [1005 Metric], Thick Film, General Purpose"
			(at 0 0 180)
			(layer "F.Fab")
			(hide yes)
			(effects
				(font
					(size 1.27 1.27)
					(thickness 0.15)
				)
			)
		)
		(property "Author" "Antmicro"
			(at 334.4 185.2 0)
			(layer "F.Fab")
			(hide yes)
			(effects
				(font
					(size 1 1)
					(thickness 0.15)
				)
			)
		)
		(property "Current" "1A"
			(at 334.4 185.2 0)
			(layer "F.Fab")
			(hide yes)
			(effects
				(font
					(size 1 1)
					(thickness 0.15)
				)
			)
		)
		(property "License" "Apache-2.0"
			(at 334.4 185.2 0)
			(layer "F.Fab")
			(hide yes)
			(effects
				(font
					(size 1 1)
					(thickness 0.15)
				)
			)
		)
		(property "MPN" "ERJ2GE0R00X"
			(at 334.4 185.2 0)
			(layer "F.Fab")
			(hide yes)
			(effects
				(font
					(size 1 1)
					(thickness 0.15)
				)
			)
		)
		(property "Manufacturer" "Panasonic"
			(at 334.4 185.2 0)
			(layer "F.Fab")
			(hide yes)
			(effects
				(font
					(size 1 1)
					(thickness 0.15)
				)
			)
		)
		(property "Tolerance" "~"
			(at 334.4 185.2 0)
			(layer "F.Fab")
			(hide yes)
			(effects
				(font
					(size 1 1)
					(thickness 0.15)
				)
			)
		)
		(property "Val" "0R"
			(at 334.4 185.2 0)
			(layer "F.Fab")
			(hide yes)
			(effects
				(font
					(size 1 1)
					(thickness 0.15)
				)
			)
		)
		(sheetname "/Peripherals/")
		(sheetfile "peripherals.kicad_sch")
		(attr smd)
		(fp_rect
			(start -0.925 -0.47)
			(end 0.925 0.47)
			(stroke
				(width 0.05)
				(type default)
			)
			(fill no)
			(layer "F.CrtYd")
		)
		(fp_rect
			(start -0.5 -0.25)
			(end 0.5 0.25)
			(stroke
				(width 0.15)
				(type solid)
			)
			(fill no)
			(layer "F.Fab")
		)
		(fp_text user "Author: Antmicro"
			(at -0.95 4.169 180)
			(layer "F.Fab")
			(effects
				(font
					(size 0.7 0.7)
					(thickness 0.15)
				)
				(justify left bottom)
			)
		)
		(fp_text user "License: Apache-2.0"
			(at -0.95 5.169 180)
			(layer "F.Fab")
			(effects
				(font
					(size 0.7 0.7)
					(thickness 0.15)
				)
				(justify left bottom)
			)
		)
		(fp_text user "${REFERENCE}"
			(at -0.95 3.168 180)
			(layer "F.Fab")
			(effects
				(font
					(size 0.7 0.7)
					(thickness 0.15)
				)
				(justify left bottom)
			)
		)
		(pad "1" smd roundrect
			(at -0.48 0 180)
			(size 0.59 0.64)
			(layers "F.Cu" "F.Mask" "F.Paste")
			(roundrect_rratio 0.25)
			(net 364 "Net-(J4-Pad40)")
			(pintype "passive")
		)
		(pad "2" smd roundrect
			(at 0.48 0 180)
			(size 0.59 0.64)
			(layers "F.Cu" "F.Mask" "F.Paste")
			(roundrect_rratio 0.25)
			(net 92 "/Peripherals/FCC1_SCL1")
			(pintype "passive")
		)
	)
)
